(kicad_pcb
	(version 20240108)
	(generator "pcbnew")
	(generator_version "8.0")
	(general
		(thickness 1.62)
		(legacy_teardrops no)
	)
	(paper "A4")
	(title_block
		(title "Jetson Orin Baseboard")
		(date "2025-03-12")
		(rev "1.3.4")
		(company "Antmicro Ltd")
		(comment 1 "www.antmicro.com")
		(comment 9 "footprints 500-504 of 677")
	)
	(layers
		(0 "F.Cu" signal)
		(1 "In1.Cu" signal)
		(2 "In2.Cu" signal)
		(3 "In3.Cu" signal)
		(4 "In4.Cu" jumper)
		(5 "In5.Cu" signal)
		(6 "In6.Cu" signal)
		(31 "B.Cu" signal)
		(32 "B.Adhes" user "B.Adhesive")
		(33 "F.Adhes" user "F.Adhesive")
		(34 "B.Paste" user)
		(35 "F.Paste" user)
		(36 "B.SilkS" user "B.Silkscreen")
		(37 "F.SilkS" user "F.Silkscreen")
		(38 "B.Mask" user)
		(39 "F.Mask" user)
		(40 "Dwgs.User" user "User.Drawings")
		(41 "Cmts.User" user "User.Comments")
		(42 "Eco1.User" user "User.Eco1")
		(43 "Eco2.User" user "User.Eco2")
		(44 "Edge.Cuts" user)
		(45 "Margin" user)
		(46 "B.CrtYd" user "B.Courtyard")
		(47 "F.CrtYd" user "F.Courtyard")
		(48 "B.Fab" user)
		(49 "F.Fab" user)
	)
	(footprint "antmicro-footprints:R_0402_1005Metric"
		(layer "B.Cu")
		(at 50.4 74.3 -90)
		(descr "Resistor SMD 0402")
		(tags "resistor SMD 0402")
		(property "Reference" "R285"
			(at 0.6 -1.4 90)
			(layer "B.SilkS")
			(effects
				(font
					(size 0.7 0.7)
					(thickness 0.15)
				)
				(justify left bottom mirror)
			)
		)
		(property "Value" "R_100k_0402"
			(at -1.011843 -1.772046 90)
			(layer "B.Fab")
			(effects
				(font
					(size 0.7 0.7)
					(thickness 0.15)
				)
				(justify left bottom mirror)
			)
		)
		(property "Footprint" "antmicro-footprints:R_0402_1005Metric"
			(at 0 0 90)
			(layer "B.Fab")
			(hide yes)
			(effects
				(font
					(size 1.27 1.27)
					(thickness 0.15)
				)
				(justify mirror)
			)
		)
		(property "Datasheet" "https://www.bourns.com/docs/product-datasheets/cr.pdf"
			(at 0 0 90)
			(layer "B.Fab")
			(hide yes)
			(effects
				(font
					(size 1.27 1.27)
					(thickness 0.15)
				)
				(justify mirror)
			)
		)
		(property "Manufacturer" "Bourns"
			(at 0 0 90)
			(unlocked yes)
			(layer "B.Fab")
			(hide yes)
			(effects
				(font
					(size 1 1)
					(thickness 0.15)
				)
				(justify mirror)
			)
		)
		(property "MPN" "CR0402-FX-1003GLF"
			(at 0 0 90)
			(unlocked yes)
			(layer "B.Fab")
			(hide yes)
			(effects
				(font
					(size 1 1)
					(thickness 0.15)
				)
				(justify mirror)
			)
		)
		(property "Val" "100k"
			(at 0 0 90)
			(unlocked yes)
			(layer "B.Fab")
			(hide yes)
			(effects
				(font
					(size 1 1)
					(thickness 0.15)
				)
				(justify mirror)
			)
		)
		(property "License" "Apache-2.0"
			(at 0 0 90)
			(unlocked yes)
			(layer "B.Fab")
			(hide yes)
			(effects
				(font
					(size 1 1)
					(thickness 0.15)
				)
				(justify mirror)
			)
		)
		(property "Author" "Antmicro"
			(at 0 0 90)
			(unlocked yes)
			(layer "B.Fab")
			(hide yes)
			(effects
				(font
					(size 1 1)
					(thickness 0.15)
				)
				(justify mirror)
			)
		)
		(property "Tolerance" "1%"
			(at 0 0 90)
			(unlocked yes)
			(layer "B.Fab")
			(hide yes)
			(effects
				(font
					(size 1 1)
					(thickness 0.15)
				)
				(justify mirror)
			)
		)
		(sheetname "Supply")
		(sheetfile "supply.kicad_sch")
		(attr smd)
		(fp_poly
			(pts
				(xy -0.925 0.47) (xy 0.925 0.47) (xy 0.925 -0.47) (xy -0.925 -0.47)
			)
			(stroke
				(width 0.05)
				(type default)
			)
			(fill none)
			(layer "B.CrtYd")
		)
		(fp_poly
			(pts
				(xy -0.5 0.25) (xy 0.5 0.25) (xy 0.5 -0.25) (xy -0.5 -0.25)
			)
			(stroke
				(width 0.15)
				(type solid)
			)
			(fill none)
			(layer "B.Fab")
		)
		(fp_text user "License: Apache-2.0"
			(at -0.949999 -5.169 90)
			(layer "B.Fab")
			(hide yes)
			(effects
				(font
					(size 0.7 0.7)
					(thickness 0.15)
				)
				(justify left bottom mirror)
			)
		)
		(fp_text user "${REFERENCE}"
			(at -0.95 -3.168 90)
			(layer "B.Fab")
			(hide yes)
			(effects
				(font
					(size 0.7 0.7)
					(thickness 0.15)
				)
				(justify left bottom mirror)
			)
		)
		(fp_text user "Author: Antmicro"
			(at -0.95 -4.169 90)
			(layer "B.Fab")
			(hide yes)
			(effects
				(font
					(size 0.7 0.7)
					(thickness 0.15)
				)
				(justify left bottom mirror)
			)
		)
		(pad "1" smd roundrect
			(at -0.48 0 270)
			(size 0.59 0.64)
			(layers "B.Cu" "B.Paste" "B.Mask")
			(roundrect_rratio 0.25)
			(net 1 "GND")
			(pintype "passive")
		)
		(pad "2" smd roundrect
			(at 0.48 0 270)
			(size 0.59 0.64)
			(layers "B.Cu" "B.Paste" "B.Mask")
			(roundrect_rratio 0.25)
			(net 799 "/Supply/PG_{HP}")
			(pintype "passive")
		)
	)
	(footprint "antmicro-footprints:R_0402_1005Metric"
		(layer "B.Cu")
		(at 88.05 103.1 -135)
		(descr "Resistor SMD 0402")
		(tags "resistor SMD 0402")
		(property "Reference" "R180"
			(at -1.52028 0.388909 45)
			(layer "B.SilkS")
			(effects
				(font
					(size 0.7 0.7)
					(thickness 0.15)
				)
				(justify left bottom mirror)
			)
		)
		(property "Value" "R_100k_0402"
			(at 0 -1.399999 45)
			(layer "B.Fab")
			(effects
				(font
					(size 0.7 0.7)
					(thickness 0.15)
				)
				(justify left bottom mirror)
			)
		)
		(property "Footprint" "antmicro-footprints:R_0402_1005Metric"
			(at 0 0 -135)
			(layer "F.Fab")
			(hide yes)
			(effects
				(font
					(size 1.27 1.27)
					(thickness 0.15)
				)
			)
		)
		(property "Datasheet" "https://www.bourns.com/docs/product-datasheets/cr.pdf"
			(at 0 0 -135)
			(layer "F.Fab")
			(hide yes)
			(effects
				(font
					(size 1.27 1.27)
					(thickness 0.15)
				)
			)
		)
		(property "Author" "Antmicro"
			(at 77.408043 238.263461 0)
			(layer "B.Fab")
			(hide yes)
			(effects
				(font
					(size 1 1)
					(thickness 0.15)
				)
				(justify mirror)
			)
		)
		(property "License" "Apache-2.0"
			(at 77.408043 238.263461 0)
			(layer "B.Fab")
			(hide yes)
			(effects
				(font
					(size 1 1)
					(thickness 0.15)
				)
				(justify mirror)
			)
		)
		(property "MPN" "CR0402-FX-1003GLF"
			(at 77.408043 238.263461 0)
			(layer "B.Fab")
			(hide yes)
			(effects
				(font
					(size 1 1)
					(thickness 0.15)
				)
				(justify mirror)
			)
		)
		(property "Manufacturer" "Bourns"
			(at 77.408043 238.263461 0)
			(layer "B.Fab")
			(hide yes)
			(effects
				(font
					(size 1 1)
					(thickness 0.15)
				)
				(justify mirror)
			)
		)
		(property "Tolerance" "1%"
			(at 77.408043 238.263461 0)
			(layer "B.Fab")
			(hide yes)
			(effects
				(font
					(size 1 1)
					(thickness 0.15)
				)
				(justify mirror)
			)
		)
		(property "Val" "100k"
			(at 77.408043 238.263461 0)
			(layer "B.Fab")
			(hide yes)
			(effects
				(font
					(size 1 1)
					(thickness 0.15)
				)
				(justify mirror)
			)
		)
		(sheetname "CSI")
		(sheetfile "csi.kicad_sch")
		(attr smd)
		(fp_poly
			(pts
				(xy -0.925 0.47) (xy 0.925 0.47) (xy 0.925 -0.47) (xy -0.925 -0.47)
			)
			(stroke
				(width 0.05)
				(type default)
			)
			(fill none)
			(layer "B.CrtYd")
		)
		(fp_poly
			(pts
				(xy -0.5 0.25) (xy 0.5 0.25) (xy 0.5 -0.25) (xy -0.5 -0.25)
			)
			(stroke
				(width 0.15)
				(type solid)
			)
			(fill none)
			(layer "B.Fab")
		)
		(fp_text user "${REFERENCE}"
			(at -0.95 -3.168 45)
			(layer "B.Fab")
			(hide yes)
			(effects
				(font
					(size 0.7 0.7)
					(thickness 0.15)
				)
				(justify left bottom mirror)
			)
		)
		(fp_text user "Author: Antmicro"
			(at -0.95 -4.169 45)
			(layer "B.Fab")
			(hide yes)
			(effects
				(font
					(size 0.7 0.7)
					(thickness 0.15)
				)
				(justify left bottom mirror)
			)
		)
		(fp_text user "License: Apache-2.0"
			(at -0.949999 -5.169 45)
			(layer "B.Fab")
			(hide yes)
			(effects
				(font
					(size 0.7 0.7)
					(thickness 0.15)
				)
				(justify left bottom mirror)
			)
		)
		(pad "1" smd roundrect
			(at -0.48 0 225)
			(size 0.59 0.64)
			(layers "B.Cu" "B.Paste" "B.Mask")
			(roundrect_rratio 0.25)
			(net 1 "GND")
			(pintype "passive")
		)
		(pad "2" smd roundrect
			(at 0.48 0 225)
			(size 0.59 0.64)
			(layers "B.Cu" "B.Paste" "B.Mask")
			(roundrect_rratio 0.25)
			(net 338 "CSIB_PEN")
			(pintype "passive")
		)
	)
	(footprint "antmicro-footprints:C_2220_5650Metric"
		(layer "B.Cu")
		(at 33.8 83.6 180)
		(descr "Capacitor SMD 2220")
		(tags "capacitor SMD 2220")
		(property "Reference" "C81"
			(at -1.85 3.12 0)
			(layer "B.SilkS")
			(effects
				(font
					(size 0.7 0.7)
					(thickness 0.15)
				)
				(justify left bottom mirror)
			)
		)
		(property "Value" "C_22u_100V_2220"
			(at 0 -3.9 0)
			(layer "B.Fab")
			(effects
				(font
					(size 0.7 0.7)
					(thickness 0.15)
				)
				(justify left bottom mirror)
			)
		)
		(property "Footprint" "antmicro-footprints:C_2220_5650Metric"
			(at 0 0 180)
			(layer "F.Fab")
			(hide yes)
			(effects
				(font
					(size 1.27 1.27)
					(thickness 0.15)
				)
			)
		)
		(property "Datasheet" "https://product.tdk.com/en/search/capacitor/ceramic/mlcc/info?part_no=C5750X7S2A226M280KB"
			(at 0 0 180)
			(layer "F.Fab")
			(hide yes)
			(effects
				(font
					(size 1.27 1.27)
					(thickness 0.15)
				)
			)
		)
		(property "Author" "Antmicro"
			(at 67.6 167.2 0)
			(layer "B.Fab")
			(hide yes)
			(effects
				(font
					(size 1 1)
					(thickness 0.15)
				)
				(justify mirror)
			)
		)
		(property "Dielectric" "X7S"
			(at 67.6 167.2 0)
			(layer "B.Fab")
			(hide yes)
			(effects
				(font
					(size 1 1)
					(thickness 0.15)
				)
				(justify mirror)
			)
		)
		(property "License" "Apache-2.0"
			(at 67.6 167.2 0)
			(layer "B.Fab")
			(hide yes)
			(effects
				(font
					(size 1 1)
					(thickness 0.15)
				)
				(justify mirror)
			)
		)
		(property "MPN" "C5750X7S2A226M280KB"
			(at 67.6 167.2 0)
			(layer "B.Fab")
			(hide yes)
			(effects
				(font
					(size 1 1)
					(thickness 0.15)
				)
				(justify mirror)
			)
		)
		(property "Manufacturer" "TDK"
			(at 67.6 167.2 0)
			(layer "B.Fab")
			(hide yes)
			(effects
				(font
					(size 1 1)
					(thickness 0.15)
				)
				(justify mirror)
			)
		)
		(property "Public" "False"
			(at 67.6 167.2 0)
			(layer "B.Fab")
			(hide yes)
			(effects
				(font
					(size 1 1)
					(thickness 0.15)
				)
				(justify mirror)
			)
		)
		(property "Val" "22u"
			(at 67.6 167.2 0)
			(layer "B.Fab")
			(hide yes)
			(effects
				(font
					(size 1 1)
					(thickness 0.15)
				)
				(justify mirror)
			)
		)
		(property "Voltage" "100V"
			(at 67.6 167.2 0)
			(layer "B.Fab")
			(hide yes)
			(effects
				(font
					(size 1 1)
					(thickness 0.15)
				)
				(justify mirror)
			)
		)
		(sheetname "Ethernet")
		(sheetfile "ethernet.kicad_sch")
		(attr smd)
		(fp_line
			(start 1.415 2.61)
			(end -1.415 2.61)
			(stroke
				(width 0.15)
				(type solid)
			)
			(layer "B.SilkS")
		)
		(fp_line
			(start 1.415 -2.61)
			(end -1.415 -2.61)
			(stroke
				(width 0.15)
				(type solid)
			)
			(layer "B.SilkS")
		)
		(fp_rect
			(start -3.7 2.95)
			(end 3.7 -2.95)
			(stroke
				(width 0.05)
				(type solid)
			)
			(fill none)
			(layer "B.CrtYd")
		)
		(fp_rect
			(start -2.85 2.5)
			(end 2.85 -2.5)
			(stroke
				(width 0.15)
				(type solid)
			)
			(fill none)
			(layer "B.Fab")
		)
		(fp_text user "${REFERENCE}"
			(at -3.7 -5.9 0)
			(layer "B.Fab")
			(hide yes)
			(effects
				(font
					(size 0.7 0.7)
					(thickness 0.15)
				)
				(justify left bottom mirror)
			)
		)
		(fp_text user "Author: Antmicro"
			(at -3.7 -7.9 0)
			(layer "B.Fab")
			(hide yes)
			(effects
				(font
					(size 0.7 0.7)
					(thickness 0.15)
				)
				(justify left bottom mirror)
			)
		)
		(fp_text user "License: Apache-2.0"
			(at -3.7 -6.9 0)
			(layer "B.Fab")
			(hide yes)
			(effects
				(font
					(size 0.7 0.7)
					(thickness 0.15)
				)
				(justify left bottom mirror)
			)
		)
		(pad "1" smd roundrect
			(at -2.55 0 180)
			(size 1.8 5.4)
			(layers "B.Cu" "B.Paste" "B.Mask")
			(roundrect_rratio 0.138889)
			(net 106 "GNDD")
			(pintype "passive")
		)
		(pad "2" smd roundrect
			(at 2.55 0 180)
			(size 1.8 5.4)
			(layers "B.Cu" "B.Paste" "B.Mask")
			(roundrect_rratio 0.138889)
			(net 105 "/Ethernet/VDD")
			(pintype "passive")
		)
	)
	(footprint "antmicro-footprints:R_Array_4x0201_Panasonic_EXB18V"
		(layer "B.Cu")
		(at 96.33 103.6)
		(property "Reference" "R36"
			(at -2.62 1.42 180)
			(layer "B.SilkS")
			(effects
				(font
					(size 0.7 0.7)
					(thickness 0.15)
				)
				(justify right bottom mirror)
			)
		)
		(property "Value" "R_4x2k2_0201_array"
			(at -1.1 -1.8 180)
			(layer "B.Fab")
			(effects
				(font
					(size 0.7 0.7)
					(thickness 0.15)
				)
				(justify left bottom mirror)
			)
		)
		(property "Footprint" "antmicro-footprints:R_Array_4x0201_Panasonic_EXB18V"
			(at 0 0 0)
			(layer "F.Fab")
			(hide yes)
			(effects
				(font
					(size 1.27 1.27)
					(thickness 0.15)
				)
			)
		)
		(property "Datasheet" "http://industrial.panasonic.com/cdbs/www-data/pdf/AOC0000/AOC0000C14.pdf"
			(at 0 0 0)
			(layer "F.Fab")
			(hide yes)
			(effects
				(font
					(size 1.27 1.27)
					(thickness 0.15)
				)
			)
		)
		(property "Author" "Antmicro"
			(at 0 0 0)
			(layer "B.Fab")
			(hide yes)
			(effects
				(font
					(size 1 1)
					(thickness 0.15)
				)
				(justify mirror)
			)
		)
		(property "License" "Apache-2.0"
			(at 0 0 0)
			(layer "B.Fab")
			(hide yes)
			(effects
				(font
					(size 1 1)
					(thickness 0.15)
				)
				(justify mirror)
			)
		)
		(property "MPN" "EXB-18V222JX"
			(at 0 0 0)
			(layer "B.Fab")
			(hide yes)
			(effects
				(font
					(size 1 1)
					(thickness 0.15)
				)
				(justify mirror)
			)
		)
		(property "Manufacturer" "Panasonic"
			(at 0 0 0)
			(layer "B.Fab")
			(hide yes)
			(effects
				(font
					(size 1 1)
					(thickness 0.15)
				)
				(justify mirror)
			)
		)
		(property "Val" "4x2k2_0201"
			(at 0 0 0)
			(layer "B.Fab")
			(hide yes)
			(effects
				(font
					(size 1 1)
					(thickness 0.15)
				)
				(justify mirror)
			)
		)
		(sheetname "CSI")
		(sheetfile "csi.kicad_sch")
		(attr smd)
		(fp_line
			(start -0.8 -0.45)
			(end -0.8 0.45)
			(stroke
				(width 0.12)
				(type solid)
			)
			(layer "B.SilkS")
		)
		(fp_line
			(start 0.8 -0.45)
			(end 0.8 0.45)
			(stroke
				(width 0.12)
				(type solid)
			)
			(layer "B.SilkS")
		)
		(fp_rect
			(start -0.898 0.66)
			(end 0.898 -0.65)
			(stroke
				(width 0.05)
				(type solid)
			)
			(fill none)
			(layer "B.CrtYd")
		)
		(fp_text user "License: Apache-2.0"
			(at -1.051 -6 180)
			(layer "B.Fab")
			(hide yes)
			(effects
				(font
					(size 0.7 0.7)
					(thickness 0.15)
				)
				(justify left bottom mirror)
			)
		)
		(fp_text user "${REFERENCE}"
			(at -1.051 -3.2 180)
			(layer "B.Fab")
			(hide yes)
			(effects
				(font
					(size 0.7 0.7)
					(thickness 0.15)
				)
				(justify left bottom mirror)
			)
		)
		(fp_text user "Author: Antmicro"
			(at -1.051 -4.599 180)
			(layer "B.Fab")
			(hide yes)
			(effects
				(font
					(size 0.7 0.7)
					(thickness 0.15)
				)
				(justify left bottom mirror)
			)
		)
		(pad "1" smd roundrect
			(at -0.6 -0.298)
			(size 0.2 0.4)
			(layers "B.Cu" "B.Paste" "B.Mask")
			(roundrect_rratio 0.25)
			(net 330 "/CSI/SCL_CAM1")
			(pinfunction "R1.1")
			(pintype "passive")
		)
		(pad "2" smd roundrect
			(at -0.202 -0.298)
			(size 0.2 0.4)
			(layers "B.Cu" "B.Paste" "B.Mask")
			(roundrect_rratio 0.25)
			(net 329 "/CSI/SDA_CAM1")
			(pinfunction "R2.1")
			(pintype "passive")
		)
		(pad "3" smd roundrect
			(at 0.2 -0.298)
			(size 0.2 0.4)
			(layers "B.Cu" "B.Paste" "B.Mask")
			(roundrect_rratio 0.25)
			(net 323 "/CSI/SCL_CAM0")
			(pinfunction "R3.1")
			(pintype "passive")
		)
		(pad "4" smd roundrect
			(at 0.598 -0.298)
			(size 0.2 0.4)
			(layers "B.Cu" "B.Paste" "B.Mask")
			(roundrect_rratio 0.25)
			(net 320 "/CSI/SDA_CAM0")
			(pinfunction "R4.1")
			(pintype "passive")
		)
		(pad "5" smd roundrect
			(at 0.598 0.3)
			(size 0.2 0.4)
			(layers "B.Cu" "B.Paste" "B.Mask")
			(roundrect_rratio 0.25)
			(net 321 "/CSI/CSIA_I2C_VCC")
			(pinfunction "R4.2")
			(pintype "passive")
		)
		(pad "6" smd roundrect
			(at 0.2 0.3)
			(size 0.2 0.4)
			(layers "B.Cu" "B.Paste" "B.Mask")
			(roundrect_rratio 0.25)
			(net 321 "/CSI/CSIA_I2C_VCC")
			(pinfunction "R3.2")
			(pintype "passive")
		)
		(pad "7" smd roundrect
			(at -0.202 0.3)
			(size 0.2 0.4)
			(layers "B.Cu" "B.Paste" "B.Mask")
			(roundrect_rratio 0.25)
			(net 321 "/CSI/CSIA_I2C_VCC")
			(pinfunction "R2.2")
			(pintype "passive")
		)
		(pad "8" smd roundrect
			(at -0.6 0.3)
			(size 0.2 0.4)
			(layers "B.Cu" "B.Paste" "B.Mask")
			(roundrect_rratio 0.25)
			(net 321 "/CSI/CSIA_I2C_VCC")
			(pinfunction "R1.2")
			(pintype "passive")
		)
	)
	(footprint "antmicro-footprints:R_0402_1005Metric"
		(layer "B.Cu")
		(at 76 110.2 -90)
		(descr "Resistor SMD 0402")
		(tags "resistor SMD 0402")
		(property "Reference" "R95"
			(at 0.76 -2.4 90)
			(layer "B.SilkS")
			(effects
				(font
					(size 0.7 0.7)
					(thickness 0.15)
				)
				(justify left bottom mirror)
			)
		)
		(property "Value" "R_1k_0402"
			(at 0 -1.4 90)
			(layer "B.Fab")
			(effects
				(font
					(size 0.7 0.7)
					(thickness 0.15)
				)
				(justify left bottom mirror)
			)
		)
		(property "Footprint" "antmicro-footprints:R_0402_1005Metric"
			(at 0 0 -90)
			(layer "F.Fab")
			(hide yes)
			(effects
				(font
					(size 1.27 1.27)
					(thickness 0.15)
				)
			)
		)
		(property "Datasheet" "https://www.bourns.com/docs/product-datasheets/cr.pdf"
			(at 0 0 -90)
			(layer "F.Fab")
			(hide yes)
			(effects
				(font
					(size 1.27 1.27)
					(thickness 0.15)
				)
			)
		)
		(property "Author" "Antmicro"
			(at -34.2 186.2 0)
			(layer "B.Fab")
			(hide yes)
			(effects
				(font
					(size 1 1)
					(thickness 0.15)
				)
				(justify mirror)
			)
		)
		(property "License" "Apache-2.0"
			(at -34.2 186.2 0)
			(layer "B.Fab")
			(hide yes)
			(effects
				(font
					(size 1 1)
					(thickness 0.15)
				)
				(justify mirror)
			)
		)
		(property "MPN" "CR0402-FX-1001GLF"
			(at -34.2 186.2 0)
			(layer "B.Fab")
			(hide yes)
			(effects
				(font
					(size 1 1)
					(thickness 0.15)
				)
				(justify mirror)
			)
		)
		(property "Manufacturer" "Bourns"
			(at -34.2 186.2 0)
			(layer "B.Fab")
			(hide yes)
			(effects
				(font
					(size 1 1)
					(thickness 0.15)
				)
				(justify mirror)
			)
		)
		(property "Tolerance" "1%"
			(at -34.2 186.2 0)
			(layer "B.Fab")
			(hide yes)
			(effects
				(font
					(size 1 1)
					(thickness 0.15)
				)
				(justify mirror)
			)
		)
		(property "Val" "1k"
			(at -34.2 186.2 0)
			(layer "B.Fab")
			(hide yes)
			(effects
				(font
					(size 1 1)
					(thickness 0.15)
				)
				(justify mirror)
			)
		)
		(sheetname "USB Debug, DP")
		(sheetfile "usb.kicad_sch")
		(attr smd exclude_from_pos_files exclude_from_bom dnp)
		(fp_rect
			(start -0.925 0.47)
			(end 0.925 -0.47)
			(stroke
				(width 0.05)
				(type default)
			)
			(fill none)
			(layer "B.CrtYd")
		)
		(fp_rect
			(start -0.5 0.25)
			(end 0.5 -0.25)
			(stroke
				(width 0.15)
				(type solid)
			)
			(fill none)
			(layer "B.Fab")
		)
		(fp_text user "${REFERENCE}"
			(at -0.95 -3.168 90)
			(layer "B.Fab")
			(hide yes)
			(effects
				(font
					(size 0.7 0.7)
					(thickness 0.15)
				)
				(justify left bottom mirror)
			)
		)
		(fp_text user "License: Apache-2.0"
			(at -0.95 -5.169 90)
			(layer "B.Fab")
			(hide yes)
			(effects
				(font
					(size 0.7 0.7)
					(thickness 0.15)
				)
				(justify left bottom mirror)
			)
		)
		(fp_text user "Author: Antmicro"
			(at -0.95 -4.169 90)
			(layer "B.Fab")
			(hide yes)
			(effects
				(font
					(size 0.7 0.7)
					(thickness 0.15)
				)
				(justify left bottom mirror)
			)
		)
		(pad "1" smd roundrect
			(at -0.48 0 270)
			(size 0.59 0.64)
			(layers "B.Cu" "B.Paste" "B.Mask")
			(roundrect_rratio 0.25)
			(net 309 "/USB Debug, DP/USBC0_EQ0")
			(pintype "passive")
		)
		(pad "2" smd roundrect
			(at 0.48 0 270)
			(size 0.59 0.64)
			(layers "B.Cu" "B.Paste" "B.Mask")
			(roundrect_rratio 0.25)
			(net 87 "+3V3")
			(pintype "passive")
		)
	)
)
